# T6G (Grand Teton) — schematic netlist excerpt (pin names and nets, part order shuffled) for the footprints in the layout excerpt that follows; sources: Cadence DE-HDL packaged netlist, KiCad conversion of 04192023_DAF0TMB3IC0_F0TG_MB_C_brd_V02_OCP.brd

C6594  Q_CAP_DIFFBUS  DIFF BUS_0.22UF 6.3V 20% X6S  pkg C0201  page 297 : \1\ = P5E_CPU0_P2_TX_BUF_C_DN<14> ; \2\ = P5E_CPU0_P2_TX_BUF_DN<14>
C890  Q_CAP_DIFFBUS  DIFF BUS_0.22UF 6.3V 20% X6S  pkg C0201  page 64 : \1\ = P5E_CPU0_P3_TX_C_DN<5> ; \2\ = P5E_CPU0_P3_TX_DN<5>
PC6537  Q_CAP  0.1UF 25V 10% X7R  pkg 0402  page 361 : A = P1V8_RETIMER_CPU1_REF ; B = GND
C824  Q_CAP_DIFFBUS  DIFF BUS_0.22UF 6.3V 20% X6S  pkg C0201  page 65 : \1\ = P5E_CPU1_P0_TX_C_DN<6> ; \2\ = P5E_CPU1_P0_TX_DN<6>

(kicad_pcb
	(version 20260206)
	(generator "pcbnew")
	(generator_version "10.0")
	(general
		(thickness 1.6)
		(legacy_teardrops no)
	)
	(paper "A4")
	(title_block
		(title "04192023_DAF0TMB3IC0_F0TG_MB_C_brd_V02_OCP.brd")
		(comment 1 "Grand Teton / footprints 3581-3584 of 8354")
	)
	(layers
		(0 "F.Cu" signal "TOP")
		(4 "In1.Cu" signal "GND")
		(6 "In2.Cu" signal "IN1")
		(8 "In3.Cu" signal "GND1")
		(10 "In4.Cu" signal "IN2")
		(12 "In5.Cu" signal "GND2")
		(14 "In6.Cu" signal "IN3")
		(16 "In7.Cu" signal "GND3")
		(18 "In8.Cu" signal "VCC")
		(20 "In9.Cu" signal "VCC1")
		(22 "In10.Cu" signal "GND4")
		(24 "In11.Cu" signal "IN4")
		(26 "In12.Cu" signal "GND5")
		(28 "In13.Cu" signal "IN5")
		(30 "In14.Cu" signal "GND6")
		(32 "In15.Cu" signal "IN6")
		(34 "In16.Cu" signal "GND7")
		(2 "B.Cu" signal "BOTTOM")
		(9 "F.Adhes" user "F.Adhesive")
		(11 "B.Adhes" user "B.Adhesive")
		(13 "F.Paste" user "Package Geometry/Pastemask Top")
		(15 "B.Paste" user "Package Geometry/Pastemask Bottom")
		(5 "F.SilkS" user "Ref Des/Silkscreen Top")
		(7 "B.SilkS" user "Ref Des/Silkscreen Bottom")
		(1 "F.Mask" user "Board Geometry/Soldermask Top")
		(3 "B.Mask" user "Board Geometry/Soldermask Bottom")
		(17 "Dwgs.User" user "User.Drawings")
		(19 "Cmts.User" user "User.Comments")
		(21 "Eco1.User" user "User.Eco1")
		(23 "Eco2.User" user "User.Eco2")
		(25 "Edge.Cuts" user "Board Geometry/Outline")
		(27 "Margin" user)
		(31 "F.CrtYd" user "Package Geometry/Place Bound Top")
		(29 "B.CrtYd" user "Package Geometry/Place Bound Bottom")
		(35 "F.Fab" user "Ref Des/Assembly Top")
		(33 "B.Fab" user "Ref Des/Assembly Bottom")
	)
	(footprint ""
		(layer "F.Cu")
		(at 413.754062 -416.899344 -90)
		(property "Reference" "C6594"
			(at 0 0 270)
			(layer "F.SilkS")
			(hide yes)
			(effects
				(font
					(size 1.27 1.27)
				)
			)
		)
		(property "Value" ""
			(at 0 0 270)
			(layer "F.Fab")
			(effects
				(font
					(size 1.27 1.27)
				)
			)
		)
		(duplicate_pad_numbers_are_jumpers no)
		(fp_line
			(start -0.299974 0.150114)
			(end -0.299974 -0.150114)
			(stroke
				(width 0.1)
				(type default)
			)
			(layer "F.Fab")
		)
		(fp_line
			(start 0.299974 0.150114)
			(end -0.299974 0.150114)
			(stroke
				(width 0.1)
				(type default)
			)
			(layer "F.Fab")
		)
		(fp_line
			(start -0.299974 -0.150114)
			(end 0.299974 -0.150114)
			(stroke
				(width 0.1)
				(type default)
			)
			(layer "F.Fab")
		)
		(fp_line
			(start 0.299974 -0.150114)
			(end 0.299974 0.150114)
			(stroke
				(width 0.1)
				(type default)
			)
			(layer "F.Fab")
		)
		(pad "1" smd rect
			(at -0.2667 0 270)
			(size 0.3048 0.381)
			(layers "F.Cu" "F.Mask" "F.Paste")
			(net "P5E_CPU0_P2_TX_BUF_C_DN<14>")
		)
		(pad "2" smd rect
			(at 0.2667 0 270)
			(size 0.3048 0.381)
			(layers "F.Cu" "F.Mask" "F.Paste")
			(net "P5E_CPU0_P2_TX_BUF_DN<14>")
		)
	)
	(footprint ""
		(layer "F.Cu")
		(at 373.811292 -381.41783 -90)
		(property "Reference" "C890"
			(at 0 0 270)
			(layer "F.SilkS")
			(hide yes)
			(effects
				(font
					(size 1.27 1.27)
				)
			)
		)
		(property "Value" ""
			(at 0 0 270)
			(layer "F.Fab")
			(effects
				(font
					(size 1.27 1.27)
				)
			)
		)
		(duplicate_pad_numbers_are_jumpers no)
		(fp_line
			(start -0.299974 0.150114)
			(end -0.299974 -0.150114)
			(stroke
				(width 0.1)
				(type default)
			)
			(layer "F.Fab")
		)
		(fp_line
			(start 0.299974 0.150114)
			(end -0.299974 0.150114)
			(stroke
				(width 0.1)
				(type default)
			)
			(layer "F.Fab")
		)
		(fp_line
			(start -0.299974 -0.150114)
			(end 0.299974 -0.150114)
			(stroke
				(width 0.1)
				(type default)
			)
			(layer "F.Fab")
		)
		(fp_line
			(start 0.299974 -0.150114)
			(end 0.299974 0.150114)
			(stroke
				(width 0.1)
				(type default)
			)
			(layer "F.Fab")
		)
		(pad "1" smd rect
			(at -0.2667 0 270)
			(size 0.3048 0.381)
			(layers "F.Cu" "F.Mask" "F.Paste")
			(net "P5E_CPU0_P3_TX_C_DN<5>")
		)
		(pad "2" smd rect
			(at 0.2667 0 270)
			(size 0.3048 0.381)
			(layers "F.Cu" "F.Mask" "F.Paste")
			(net "P5E_CPU0_P3_TX_DN<5>")
		)
	)
	(footprint ""
		(layer "F.Cu")
		(at 52.413154 -370.57203 -90)
		(property "Reference" "C824"
			(at 0 0 270)
			(layer "F.SilkS")
			(hide yes)
			(effects
				(font
					(size 1.27 1.27)
				)
			)
		)
		(property "Value" ""
			(at 0 0 270)
			(layer "F.Fab")
			(effects
				(font
					(size 1.27 1.27)
				)
			)
		)
		(duplicate_pad_numbers_are_jumpers no)
		(fp_line
			(start -0.299974 0.150114)
			(end -0.299974 -0.150114)
			(stroke
				(width 0.1)
				(type default)
			)
			(layer "F.Fab")
		)
		(fp_line
			(start 0.299974 0.150114)
			(end -0.299974 0.150114)
			(stroke
				(width 0.1)
				(type default)
			)
			(layer "F.Fab")
		)
		(fp_line
			(start -0.299974 -0.150114)
			(end 0.299974 -0.150114)
			(stroke
				(width 0.1)
				(type default)
			)
			(layer "F.Fab")
		)
		(fp_line
			(start 0.299974 -0.150114)
			(end 0.299974 0.150114)
			(stroke
				(width 0.1)
				(type default)
			)
			(layer "F.Fab")
		)
		(pad "1" smd rect
			(at -0.2667 0 270)
			(size 0.3048 0.381)
			(layers "F.Cu" "F.Mask" "F.Paste")
			(net "P5E_CPU1_P0_TX_C_DN<6>")
		)
		(pad "2" smd rect
			(at 0.2667 0 270)
			(size 0.3048 0.381)
			(layers "F.Cu" "F.Mask" "F.Paste")
			(net "P5E_CPU1_P0_TX_DN<6>")
		)
	)
	(footprint ""
		(layer "F.Cu")
		(at 227.59162 -291.863526 180)
		(property "Reference" "PC6537"
			(at 0 0 180)
			(layer "F.SilkS")
			(hide yes)
			(effects
				(font
					(size 1.27 1.27)
				)
			)
		)
		(property "Value" ""
			(at 0 0 180)
			(layer "F.Fab")
			(effects
				(font
					(size 1.27 1.27)
				)
			)
		)
		(duplicate_pad_numbers_are_jumpers no)
		(fp_line
			(start 0.7874 0.4064)
			(end -0.7874 0.4064)
			(stroke
				(width 0.1524)
				(type default)
			)
			(layer "F.SilkS")
		)
		(fp_line
			(start 0.7874 -0.4064)
			(end 0.7874 0.4064)
			(stroke
				(width 0.1524)
				(type default)
			)
			(layer "F.SilkS")
		)
		(fp_line
			(start -0.7874 0.4064)
			(end -0.7874 -0.4064)
			(stroke
				(width 0.1524)
				(type default)
			)
			(layer "F.SilkS")
		)
		(fp_line
			(start -0.7874 -0.4064)
			(end 0.7874 -0.4064)
			(stroke
				(width 0.1524)
				(type default)
			)
			(layer "F.SilkS")
		)
		(fp_line
			(start 0.67945 0.3048)
			(end 0.120396 0.3048)
			(stroke
				(width 0.1)
				(type default)
			)
			(layer "F.Fab")
		)
		(fp_line
			(start 0.67945 -0.3048)
			(end 0.67945 0.3048)
			(stroke
				(width 0.1)
				(type default)
			)
			(layer "F.Fab")
		)
		(fp_line
			(start 0.12065 -0.2794)
			(end 0.12065 -0.3048)
			(stroke
				(width 0.1)
				(type default)
			)
			(layer "F.Fab")
		)
		(fp_line
			(start 0.12065 -0.3048)
			(end 0.67945 -0.3048)
			(stroke
				(width 0.1)
				(type default)
			)
			(layer "F.Fab")
		)
		(fp_line
			(start 0.120396 0.3048)
			(end 0.120396 0.2794)
			(stroke
				(width 0.1)
				(type default)
			)
			(layer "F.Fab")
		)
		(fp_line
			(start 0.120396 0.2794)
			(end -0.12065 0.2794)
			(stroke
				(width 0.1)
				(type default)
			)
			(layer "F.Fab")
		)
		(fp_line
			(start -0.12065 0.3048)
			(end -0.67945 0.3048)
			(stroke
				(width 0.1)
				(type default)
			)
			(layer "F.Fab")
		)
		(fp_line
			(start -0.12065 0.2794)
			(end -0.12065 0.3048)
			(stroke
				(width 0.1)
				(type default)
			)
			(layer "F.Fab")
		)
		(fp_line
			(start -0.12065 -0.2794)
			(end 0.12065 -0.2794)
			(stroke
				(width 0.1)
				(type default)
			)
			(layer "F.Fab")
		)
		(fp_line
			(start -0.12065 -0.305054)
			(end -0.12065 -0.2794)
			(stroke
				(width 0.1)
				(type default)
			)
			(layer "F.Fab")
		)
		(fp_line
			(start -0.67945 0.3048)
			(end -0.67945 -0.305054)
			(stroke
				(width 0.1)
				(type default)
			)
			(layer "F.Fab")
		)
		(fp_line
			(start -0.67945 -0.305054)
			(end -0.12065 -0.305054)
			(stroke
				(width 0.1)
				(type default)
			)
			(layer "F.Fab")
		)
		(pad "1" smd circle
			(at -0.40005 0 180)
			(size 0 0)
			(layers "F.Cu" "F.Mask" "F.Paste")
			(net "P1V8_RETIMER_CPU1_REF")
		)
		(pad "2" smd circle
			(at 0.40005 0 180)
			(size 0 0)
			(layers "F.Cu" "F.Mask" "F.Paste")
			(net "GND")
		)
	)
)
